# S9S_MB_2U (Grand Teton) — schematic netlist excerpt (pin names and nets, part order shuffled) for the footprints in the layout excerpt that follows; sources: Cadence DE-HDL packaged netlist, KiCad conversion of 03242023_DA0F0TMBIJ0_F0T_Motherboard_J_brd_V01_OCP.brd

Q95  MOSFET_NCH_DUAL  PJT138K IC  pkg SOT363XD  page 190
  S1  = GND
  G1  = HDD_ACTIVITY_BUF
  D2  = NC_Q95_D2
  S2  = NC_Q95_S2
  G2  = NC_Q95_G2
  D1  = HDD_ACTIVITY_BUF_N

PC1285  Q_CAP  22UF 4V 20% X6S  pkg C0805  page 300 : A = PVNN_MAIN_CPU1 ; B = GND

(kicad_pcb
	(version 20260206)
	(generator "pcbnew")
	(generator_version "10.0")
	(general
		(thickness 1.6)
		(legacy_teardrops no)
	)
	(paper "A4")
	(title_block
		(title "03242023_DA0F0TMBIJ0_F0T_Motherboard_J_brd_V01_OCP.brd")
		(comment 1 "Grand Teton / footprints 2371-2372 of 6105")
	)
	(layers
		(0 "F.Cu" signal "TOP")
		(4 "In1.Cu" signal "GND")
		(6 "In2.Cu" signal "IN1")
		(8 "In3.Cu" signal "GND1")
		(10 "In4.Cu" signal "IN2")
		(12 "In5.Cu" signal "GND2")
		(14 "In6.Cu" signal "IN3")
		(16 "In7.Cu" signal "GND3")
		(18 "In8.Cu" signal "VCC")
		(20 "In9.Cu" signal "VCC1")
		(22 "In10.Cu" signal "GND4")
		(24 "In11.Cu" signal "IN4")
		(26 "In12.Cu" signal "GND5")
		(28 "In13.Cu" signal "IN5")
		(30 "In14.Cu" signal "GND6")
		(32 "In15.Cu" signal "IN6")
		(34 "In16.Cu" signal "GND7")
		(2 "B.Cu" signal "BOTTOM")
		(9 "F.Adhes" user "F.Adhesive")
		(11 "B.Adhes" user "B.Adhesive")
		(13 "F.Paste" user "Package Geometry/Pastemask Top")
		(15 "B.Paste" user "Package Geometry/Pastemask Bottom")
		(5 "F.SilkS" user "Ref Des/Silkscreen Top")
		(7 "B.SilkS" user "Ref Des/Silkscreen Bottom")
		(1 "F.Mask" user "Board Geometry/Soldermask Top")
		(3 "B.Mask" user "Board Geometry/Soldermask Bottom")
		(17 "Dwgs.User" user "User.Drawings")
		(19 "Cmts.User" user "User.Comments")
		(21 "Eco1.User" user "User.Eco1")
		(23 "Eco2.User" user "User.Eco2")
		(25 "Edge.Cuts" user "Board Geometry/Outline")
		(27 "Margin" user)
		(31 "F.CrtYd" user "Package Geometry/Place Bound Top")
		(29 "B.CrtYd" user "Package Geometry/Place Bound Bottom")
		(35 "F.Fab" user "Ref Des/Assembly Top")
		(33 "B.Fab" user "Ref Des/Assembly Bottom")
	)
	(footprint ""
		(layer "F.Cu")
		(at 136.07288 -46.065948)
		(property "Reference" "Q95"
			(at -1.4224 -1.768348 0)
			(unlocked yes)
			(layer "F.SilkS")
			(effects
				(font
					(size 0.7874 0.5842)
					(thickness 0.1524)
				)
				(justify left)
			)
		)
		(property "Value" ""
			(at 0 0 0)
			(layer "F.Fab")
			(effects
				(font
					(size 1.27 1.27)
				)
			)
		)
		(duplicate_pad_numbers_are_jumpers no)
		(fp_line
			(start -1.332738 -1.100074)
			(end -0.4826 -1.100074)
			(stroke
				(width 0.1524)
				(type default)
			)
			(layer "F.SilkS")
		)
		(fp_line
			(start -1.332738 1.100074)
			(end -1.332738 -1.100074)
			(stroke
				(width 0.1524)
				(type default)
			)
			(layer "F.SilkS")
		)
		(fp_line
			(start -0.4826 -1.100074)
			(end 0 -0.541274)
			(stroke
				(width 0.1524)
				(type default)
			)
			(layer "F.SilkS")
		)
		(fp_line
			(start 0 -0.541274)
			(end 0.4826 -1.100074)
			(stroke
				(width 0.1524)
				(type default)
			)
			(layer "F.SilkS")
		)
		(fp_line
			(start 0.4826 -1.100074)
			(end 1.332738 -1.100074)
			(stroke
				(width 0.1524)
				(type default)
			)
			(layer "F.SilkS")
		)
		(fp_line
			(start 1.332738 -1.100074)
			(end 1.332738 1.100074)
			(stroke
				(width 0.1524)
				(type default)
			)
			(layer "F.SilkS")
		)
		(fp_line
			(start 1.332738 1.100074)
			(end -1.332738 1.100074)
			(stroke
				(width 0.1524)
				(type default)
			)
			(layer "F.SilkS")
		)
		(fp_poly
			(pts
				(xy -2.2352 -1.001014) (xy -1.533144 -0.649986) (xy -2.2352 -0.298958)
			)
			(stroke
				(width 0)
				(type default)
			)
			(fill yes)
			(layer "F.SilkS")
		)
		(fp_line
			(start -0.674878 -1.100074)
			(end 0.674878 -1.100074)
			(stroke
				(width 0.1)
				(type default)
			)
			(layer "F.Fab")
		)
		(fp_line
			(start -0.674878 1.100074)
			(end -0.674878 -1.100074)
			(stroke
				(width 0.1)
				(type default)
			)
			(layer "F.Fab")
		)
		(fp_line
			(start 0.674878 -1.100074)
			(end 0.674878 1.100074)
			(stroke
				(width 0.1)
				(type default)
			)
			(layer "F.Fab")
		)
		(fp_line
			(start 0.674878 1.100074)
			(end -0.674878 1.100074)
			(stroke
				(width 0.1)
				(type default)
			)
			(layer "F.Fab")
		)
		(fp_poly
			(pts
				(xy -2.2352 -0.298958) (xy -2.2352 -1.001014) (xy -1.533144 -0.649986)
			)
			(stroke
				(width 0)
				(type default)
			)
			(fill yes)
			(layer "F.Fab")
		)
		(pad "1" smd rect
			(at -0.94996 -0.649986 90)
			(size 0.4318 0.508)
			(layers "F.Cu" "F.Mask" "F.Paste")
			(net "GND")
		)
		(pad "2" smd rect
			(at -0.94996 0 90)
			(size 0.4318 0.508)
			(layers "F.Cu" "F.Mask" "F.Paste")
			(net "HDD_ACTIVITY_BUF")
		)
		(pad "3" smd rect
			(at -0.94996 0.649986 90)
			(size 0.4318 0.508)
			(layers "F.Cu" "F.Mask" "F.Paste")
			(net "NC_Q95_D2")
		)
		(pad "4" smd rect
			(at 0.94996 0.649986 90)
			(size 0.4318 0.508)
			(layers "F.Cu" "F.Mask" "F.Paste")
			(net "NC_Q95_S2")
		)
		(pad "5" smd rect
			(at 0.94996 0 90)
			(size 0.4318 0.508)
			(layers "F.Cu" "F.Mask" "F.Paste")
			(net "NC_Q95_G2")
		)
		(pad "6" smd rect
			(at 0.94996 -0.649986 90)
			(size 0.4318 0.508)
			(layers "F.Cu" "F.Mask" "F.Paste")
			(net "HDD_ACTIVITY_BUF_N")
		)
	)
	(footprint ""
		(layer "F.Cu")
		(at 36.84143 -176.480978)
		(property "Reference" "PC1285"
			(at 0 0 0)
			(layer "F.SilkS")
			(hide yes)
			(effects
				(font
					(size 1.27 1.27)
				)
			)
		)
		(property "Value" ""
			(at 0 0 0)
			(layer "F.Fab")
			(effects
				(font
					(size 1.27 1.27)
				)
			)
		)
		(duplicate_pad_numbers_are_jumpers no)
		(fp_line
			(start -1.524 -0.762)
			(end 1.524 -0.762)
			(stroke
				(width 0.1524)
				(type default)
			)
			(layer "F.SilkS")
		)
		(fp_line
			(start -1.524 0.762)
			(end -1.524 -0.762)
			(stroke
				(width 0.1524)
				(type default)
			)
			(layer "F.SilkS")
		)
		(fp_line
			(start 1.524 -0.762)
			(end 1.524 0.762)
			(stroke
				(width 0.1524)
				(type default)
			)
			(layer "F.SilkS")
		)
		(fp_line
			(start 1.524 0.762)
			(end -1.524 0.762)
			(stroke
				(width 0.1524)
				(type default)
			)
			(layer "F.SilkS")
		)
		(fp_line
			(start -1.1049 -0.724916)
			(end -1.1049 0.724916)
			(stroke
				(width 0.1)
				(type default)
			)
			(layer "F.Fab")
		)
		(fp_line
			(start -1.1049 0.724916)
			(end 1.1049 0.724916)
			(stroke
				(width 0.1)
				(type default)
			)
			(layer "F.Fab")
		)
		(fp_line
			(start 1.1049 -0.724916)
			(end -1.1049 -0.724916)
			(stroke
				(width 0.1)
				(type default)
			)
			(layer "F.Fab")
		)
		(fp_line
			(start 1.1049 0.724916)
			(end 1.1049 -0.724916)
			(stroke
				(width 0.1)
				(type default)
			)
			(layer "F.Fab")
		)
		(pad "1" smd rect
			(at -0.889 0 180)
			(size 1.016 1.27)
			(layers "F.Cu" "F.Mask" "F.Paste")
			(net "PVNN_MAIN_CPU1")
		)
		(pad "2" smd rect
			(at 0.889 0 180)
			(size 1.016 1.27)
			(layers "F.Cu" "F.Mask" "F.Paste")
			(net "GND")
		)
	)
)
